# T6G (Grand Teton) — schematic parts with pin connectivity, parts 5034–5188 of 8303; source: Cadence DE-HDL packaged netlist (pstxprt.dat, pstxnet.dat, pstchip.dat)

R310  Q_RES  1K 1% CHIP  pkg 0402LF  page 105 : 1 = PWRGD_CHH_CPU1_DIMM ; 2 = PWRGD_CHGL_CPU1
R311  Q_RES  1K 1% CHIP  pkg 0402LF  page 106 : 1 = PWRGD_CHI_CPU1_DIMM ; 2 = PWRGD_CHGL_CPU1
R312  Q_RES  1K 1% CHIP  pkg 0402LF  page 107 : 1 = PWRGD_CHJ_CPU1_DIMM ; 2 = PWRGD_CHGL_CPU1
R313  Q_RES  1K 1% CHIP  pkg 0402LF  page 108 : 1 = PWRGD_CHK_CPU1_DIMM ; 2 = PWRGD_CHGL_CPU1
R314  Q_RES  1K 1% CHIP  pkg 0402LF  page 109 : 1 = PWRGD_CHL_CPU1_DIMM ; 2 = PWRGD_CHGL_CPU1
R315  Q_RES  49.9 1% CHIP  pkg 0402LF  page 193 : 1 = PVDDCR_CPU0_P0_RESET_N ; 2 = PVDDCR_CPU0_P0_RESET_N_R
R316  Q_RES  10K 1% EMPTY  pkg 0402LF  page 250 : 1 = P3V3_AUX ; 2 = PCA9548_PCIE3_ADDR2
R317  Q_RES  1K 1% CHIP  pkg 0402LF  page 250 : 1 = PCA9548_PCIE3_ADDR2 ; 2 = GND
R318  Q_RES  10K 1% EMPTY  pkg 0402LF  page 250 : 1 = P3V3_AUX ; 2 = PCA9548_PCIE3_ADDR1
R319  Q_RES  1K 1% CHIP  pkg 0402LF  page 250 : 1 = PCA9548_PCIE3_ADDR1 ; 2 = GND
R320  Q_RES  10K 1% EMPTY  pkg 0402LF  page 250 : 1 = P3V3_AUX ; 2 = PCA9548_PCIE3_ADDR0
R321  Q_RES  0 5% CHIP  pkg 0402LF  page 150 : 1 = SCM_IRQ_N ; 2 = IRQ0_A56
R322  Q_RES  1K 1% EMPTY  pkg 0402LF  page 160 : 1 = PVDD11_S3_P0 ; 2 = SMB_CPU0_CPU1_APML_BUF2_SCL_R2
R323  Q_RES  0 5% EMPTY  pkg 0402LF  page 161 : 1 = SMB_CPU0_CPU1_APML_SDA_R2 ; 2 = SMB_CPU0_CPU1_APML_MUX1_SDA
R324  Q_RES  0 5% EMPTY  pkg 0402LF  page 161 : 1 = SMB_CPU0_CPU1_APML_SCL_R2 ; 2 = SMB_CPU0_CPU1_APML_MUX1_SCL
R325  Q_RES  0 5% CHIP  pkg 0402LF  page 161 : 1 = SMB_CPU0_CPU1_APML_SCL_R2 ; 2 = SMB_CPU0_CPU1_APML_MUX2_SCL
R326  Q_RES  0 5% CHIP  pkg 0402LF  page 161 : 1 = SMB_CPU0_CPU1_APML_SDA_R2 ; 2 = SMB_CPU0_CPU1_APML_MUX2_SDA
R327  Q_RES  0 5% CHIP  pkg 0402LF  page 161 : 1 = SMB_APML_CPU0_MUX2_SCL ; 2 = SMB_APML_CPU0_SCL
R328  Q_RES  0 5% CHIP  pkg 0402LF  page 161 : 1 = SMB_APML_CPU0_MUX2_SDA ; 2 = SMB_APML_CPU0_SDA
R329  Q_RES  2K 1% EMPTY  pkg 0402LF  page 151 : 1 = SMB_PMBUS_3V3AUX_SDA ; 2 = P3V3_AUX
R330  Q_RES  2.2K 5% EMPTY  pkg 0402LF  page 151 : 1 = SMB_FAN_3V3AUX_SCL ; 2 = P3V3_AUX
R331  Q_RES  2.2K 5% EMPTY  pkg 0402LF  page 151 : 1 = SMB_FAN_3V3AUX_SDA ; 2 = P3V3_AUX
R332  Q_RES  2.2K 5% EMPTY  pkg 0402LF  page 151 : 1 = I3C_BMC_SWB_SCL ; 2 = P3V3_AUX
R333  Q_RES  0 5% CHIP  pkg 0402LF  page 188 : 1 = FM_P5V_EN ; 2 = VR_P5V_EN
R334  Q_RES  100K 1% CHIP  pkg 0402LF  page 188 : 1 = VR_P5V_EN ; 2 = GND
R335  Q_RES  10K 1% CHIP  pkg 0402LF  page 188 : 1 = P12V_AUX ; 2 = VR_P5V_EN_D_R
R336  Q_RES  100K 1% CHIP  pkg 0402LF  page 188 : 1 = P12V_AUX ; 2 = VR_P5V_EN_N
R337  Q_RES  0 5% CHIP  pkg 0402LF  page 161 : 1 = SMB_APML_CPU1_MUX2_SCL ; 2 = SMB_APML_CPU1_SCL
R338  Q_RES  0 5% CHIP  pkg 0402LF  page 161 : 1 = SMB_APML_CPU1_MUX2_SDA ; 2 = SMB_APML_CPU1_SDA
R339  Q_RES  49.9 1% EMPTY  pkg 0201LF  page 180 : 1 = USB2_CPU0_P0_DP ; 2 = GND
R340  Q_RES  49.9 1% EMPTY  pkg 0201LF  page 180 : 1 = USB2_CPU0_P0_DN ; 2 = GND
R341  Q_RES  51 5% EMPTY  pkg 0402LF  page 180 : 1 = USB3_CPU0_BMC_TX_DP ; 2 = GND
R342  Q_RES  51 5% EMPTY  pkg 0402LF  page 180 : 1 = USB3_CPU0_BMC_TX_DN ; 2 = GND
R343  Q_RES  49.9 1% EMPTY  pkg 0201LF  page 180 : 1 = USB2_CPU0_P0_R2_DP ; 2 = GND
R344  Q_RES  49.9 1% EMPTY  pkg 0201LF  page 180 : 1 = USB3_CPU0_BMC_TX_C2_DP ; 2 = GND
R345  Q_RES  49.9 1% EMPTY  pkg 0201LF  page 180 : 1 = USB2_CPU0_P0_R2_DN ; 2 = GND
R346  Q_RES  49.9 1% EMPTY  pkg 0201LF  page 180 : 1 = USB3_CPU0_BMC_TX_C2_DN ; 2 = GND
R347  Q_RES  33.2 1% CHIP  pkg 0402LF  page 151 : 1 = SMB_SML1_PMBUS_HSC_SCL ; 2 = SMB_SML1_PMBUS_HSC_R1_SCL
R348  Q_RES  33.2 1% CHIP  pkg 0402LF  page 151 : 1 = SMB_SML1_PMBUS_HSC_SDA ; 2 = SMB_SML1_PMBUS_HSC_R1_SDA
R349  Q_RES  33 5% CHIP  pkg 0402LF  page 151 : 1 = SMB_SCM_2_R2_SCL ; 2 = SMB_SCM_2_R5_SCL
R350  Q_RES  33 5% CHIP  pkg 0402LF  page 151 : 1 = SMB_SCM_2_R2_SDA ; 2 = SMB_SCM_2_R5_SDA
R351  Q_RES  33 5% CHIP  pkg 0402LF  page 151 : 1 = SMB_SCM_2_R5_SCL ; 2 = SMB_SCM_2_R6_SCL
R352  Q_RES  33 5% CHIP  pkg 0402LF  page 151 : 1 = SMB_SCM_2_R5_SDA ; 2 = SMB_SCM_2_R6_SDA
R353  Q_RES  0 5% CHIP  pkg 0402LF  page 267 : 1 = P12V_HSC_T_CRIT_N ; 2 = P12V_HSC_T_CRIT_R_N
R354  Q_RES  10.5K 1% CHIP  pkg 0402LF  page 267 : 1 = P3V3_AUX ; 2 = P12V_HSC_T_CRIT_R_N
R355  Q_RES  10.5K 1% CHIP  pkg 0402LF  page 267 : 1 = P3V3_AUX ; 2 = P12V_HSC_TEMP_ALERT_R_N
R356  Q_RES  0 5% CHIP  pkg 0402LF  page 27 : 1 = CPU0_XTRIG_R2_L6 ; 2 = CPU0_XTRIG_L6
R357  Q_RES  0 5% CHIP  pkg 0402LF  page 27 : 1 = CPU0_XTRIG_R2_L7 ; 2 = CPU0_XTRIG_L7
R358  Q_RES  0 5% EMPTY  pkg 0402LF  page 161 : 1 = SMB_CPU0_CPU1_SEC_SCL_R2 ; 2 = SMB_CPU1_SEC_R_SCL
R359  Q_RES  1K 1% CHIP  pkg 0402LF  page 161 : 1 = PVDD11_S3_P1 ; 2 = SMB_APML_CPU1_SDA
R360  Q_RES  1K 1% CHIP  pkg 0402LF  page 161 : 1 = PVDD11_S3_P0 ; 2 = SMB_APML_CPU0_SDA
R361  Q_RES  4.7K 5% EMPTY  pkg 0402LF  page 160 : 1 = P3V3 ; 2 = SMB_CPU0_CPU1_APML_BUF1_SCL_R2
R362  Q_RES  1K 1% CHIP  pkg 0402LF  page 161 : 1 = PVDD11_S3_P1 ; 2 = SMB_APML_CPU1_SCL
R363  Q_RES  1K 1% CHIP  pkg 0402LF  page 161 : 1 = PVDD11_S3_P0 ; 2 = SMB_APML_CPU0_SCL
R364  Q_RES  0 5% CHIP  pkg 0402LF  page 151 : 1 = P3V_BAT_R ; 2 = SCM_VDD_RTC
R365  Q_RES  4.7K 5% EMPTY  pkg 0402LF  page 160 : 1 = P3V3 ; 2 = SMB_CPU0_CPU1_APML_BUF1_SDA_R2
R366  Q_RES  1K 1% CHIP  pkg 0402LF  page 161 : 1 = PVDD18_S5_P1 ; 2 = SMB_CPU1_SEC_SCL
R367  Q_RES  1K 1% CHIP  pkg 0402LF  page 161 : 1 = PVDD18_S5_P0 ; 2 = SMB_CPU0_SEC_SCL
R368  Q_RES  4.7K 5% EMPTY  pkg 0402LF  page 160 : 1 = PVDD18_S5_P0 ; 2 = SMB_CPU0_CPU1_SEC_SCL_R2
R369  Q_RES  1K 1% CHIP  pkg 0402LF  page 161 : 1 = PVDD18_S5_P1 ; 2 = SMB_CPU1_SEC_SDA
R370  Q_RES  1K 1% CHIP  pkg 0402LF  page 161 : 1 = PVDD18_S5_P0 ; 2 = SMB_CPU0_SEC_SDA
R371  Q_RES  33 5% CHIP  pkg 0402LF  page 81 : 1 = FPGA_DEBUG_LED_CTRL ; 2 = FM_FPGA_DEBUG_LED_CTRL
R372  Q_RES  33 5% CHIP  pkg 0402LF  page 81 : 1 = P12V_ALL_PWROK_R ; 2 = P12V_ALL_PWROK
R373  Q_RES  0 5% EMPTY  pkg 0402LF  page 57 : 1 = P1V5_BAT ; 2 = CPU1_VDDBT_RTC_G
R374  Q_RES  0 5% CHIP  pkg 0402LF  page 57 : 1 = PVDD18_S5_P1 ; 2 = CPU1_VDDBT_RTC_G
R375  Q_RES  15 1% CHIP  pkg 0402LF  page 10 : 1 = M_A_CPU0_ALERT_N ; 2 = M_A_CPU0_ALERT_R_N
R376  Q_RES  15 1% CHIP  pkg 0402LF  page 11 : 1 = M_B_CPU0_ALERT_N ; 2 = M_B_CPU0_ALERT_R_N
R377  Q_RES  15 1% CHIP  pkg 0402LF  page 12 : 1 = M_C_CPU0_ALERT_N ; 2 = M_C_CPU0_ALERT_R_N
R378  Q_RES  15 1% CHIP  pkg 0402LF  page 13 : 1 = M_D_CPU0_ALERT_N ; 2 = M_D_CPU0_ALERT_R_N
R379  Q_RES  15 1% CHIP  pkg 0402LF  page 14 : 1 = M_E_CPU0_ALERT_N ; 2 = M_E_CPU0_ALERT_R_N
R380  Q_RES  15 1% CHIP  pkg 0402LF  page 15 : 1 = M_F_CPU0_ALERT_N ; 2 = M_F_CPU0_ALERT_R_N
R381  Q_RES  15 1% CHIP  pkg 0402LF  page 16 : 1 = M_G_CPU0_ALERT_N ; 2 = M_G_CPU0_ALERT_R_N
R382  Q_RES  15 1% CHIP  pkg 0402LF  page 17 : 1 = M_H_CPU0_ALERT_N ; 2 = M_H_CPU0_ALERT_R_N
R383  Q_RES  15 1% CHIP  pkg 0402LF  page 18 : 1 = M_I_CPU0_ALERT_N ; 2 = M_I_CPU0_ALERT_R_N
R384  Q_RES  15 1% CHIP  pkg 0402LF  page 19 : 1 = M_J_CPU0_ALERT_N ; 2 = M_J_CPU0_ALERT_R_N
R385  Q_RES  15 1% CHIP  pkg 0402LF  page 20 : 1 = M_K_CPU0_ALERT_N ; 2 = M_K_CPU0_ALERT_R_N
R386  Q_RES  15 1% CHIP  pkg 0402LF  page 21 : 1 = M_L_CPU0_ALERT_N ; 2 = M_L_CPU0_ALERT_R_N
R387  Q_RES  2.2K 5% CHIP  pkg 0402LF  page 27 : 1 = P3V3_AUX ; 2 = CPU0_CORETYPE2
R388  Q_RES  2.2K 5% CHIP  pkg 0402LF  page 27 : 1 = P3V3_AUX ; 2 = CPU0_CORETYPE1
R389  Q_RES  2.2K 5% CHIP  pkg 0402LF  page 27 : 1 = P3V3_AUX ; 2 = CPU0_SP5R4
R390  Q_RES  2.2K 5% CHIP  pkg 0402LF  page 27 : 1 = P3V3_AUX ; 2 = CPU0_CORETYPE0
R391  Q_RES  2.2K 5% CHIP  pkg 0402LF  page 27 : 1 = P3V3_AUX ; 2 = CPU0_SP5R3
R392  Q_RES  2.2K 5% EMPTY  pkg 0402LF  page 27 : 1 = PVDD18_S5_P0 ; 2 = CPU0_SA0
R393  Q_RES  2.2K 5% CHIP  pkg 0402LF  page 27 : 1 = CPU0_SA0 ; 2 = GND
R394  Q_RES  2.2K 5% CHIP  pkg 0402LF  page 27 : 1 = CPU0_SA1 ; 2 = GND
R395  Q_RES  0 5% CHIP  pkg 0402LF  page 81 : 1 = FM_SPD_CPU0_SWITCH_CTRL_R_N ; 2 = FM_SPD_CPU0_SWITCH_CTRL_N
R396  Q_RES  2.2K 5% CHIP  pkg 0402LF  page 27 : 1 = P3V3_AUX ; 2 = CPU0_SP5R2
R397  Q_RES  2.2K 5% CHIP  pkg 0402LF  page 27 : 1 = P3V3_AUX ; 2 = CPU0_SP5R1
R398  Q_RES  1K 1% CHIP  pkg 0402LF  page 27 : 1 = PVDD18_S5_P0 ; 2 = JTAG_CPU0_TDO
R399  Q_RES  1K 1% CHIP  pkg 0402LF  page 27 : 1 = PVDD18_S5_P0 ; 2 = JTAG_CPU0_TDI
R400  Q_RES  1K 1% CHIP  pkg 0402LF  page 27 : 1 = PVDD18_S5_P0 ; 2 = JTAG_CPU0_TRST_N
R401  Q_RES  1K 1% CHIP  pkg 0402LF  page 27 : 1 = PVDD18_S5_P0 ; 2 = JTAG_CPU0_TCK
R402  Q_RES  1K 1% CHIP  pkg 0402LF  page 27 : 1 = PVDD18_S5_P0 ; 2 = JTAG_CPU0_TMS
R403  Q_RES  1K 1% CHIP  pkg 0402LF  page 27 : 1 = PVDD18_S5_P0 ; 2 = JTAG_CPU0_DBREQ_N
R404  Q_RES  0 5% CHIP  pkg 0402LF  page 27 : 1 = JTAG_CPU0_R_TDO ; 2 = JTAG_CPU0_TDO
R405  Q_RES  0 5% CHIP  pkg 0402LF  page 27 : 1 = UART_CPU0_UART0_TX ; 2 = UART_CPU0_UART0_R_TX
R406  Q_RES  4.7K 5% EMPTY  pkg 0402LF  page 160 : 1 = PVDD18_S5_P0 ; 2 = SMB_CPU0_CPU1_SEC_SDA_R2
R407  Q_RES  0 5% CHIP  pkg 0402LF  page 80 : 1 = P12V_OCP_V3_2_PLD_PWRGD ; 2 = HP_LVC3_OCP_V3_2_P12V_PWRGD_R
R408  Q_RES  2.2K 5% CHIP  pkg 0402LF  page 27 : 1 = CPU0_BP0 ; 2 = PVDD18_S5_P0
R409  Q_RES  2.2K 5% CHIP  pkg 0402LF  page 27 : 1 = CPU0_BP1 ; 2 = PVDD18_S5_P0
R410  Q_RES  2.2K 5% CHIP  pkg 0402LF  page 27 : 1 = CPU0_BP2 ; 2 = PVDD18_S5_P0
R411  Q_RES  2.2K 5% CHIP  pkg 0402LF  page 27 : 1 = CPU0_BP3 ; 2 = PVDD18_S5_P0
R412  Q_RES  2.2K 5% CHIP  pkg 0402LF  page 27 : 1 = CPU0_PROCHOT_N ; 2 = PVDD18_S5_P0
R413  Q_RES  2.2K 5% CHIP  pkg 0402LF  page 27 : 1 = CPU0_XTRIG_L4 ; 2 = PVDD18_S5_P0
R414  Q_RES  2.2K 5% CHIP  pkg 0402LF  page 27 : 1 = CPU0_XTRIG_L5 ; 2 = PVDD18_S5_P0
R415  Q_RES  2.2K 5% CHIP  pkg 0402LF  page 27 : 1 = CPU0_XTRIG_L6 ; 2 = PVDD18_S5_P0
R416  Q_RES  2.2K 5% CHIP  pkg 0402LF  page 27 : 1 = CPU0_XTRIG_L7 ; 2 = PVDD18_S5_P0
R417  Q_RES  2.2K 5% CHIP  pkg 0402LF  page 27 : 1 = CPU0_THERMTRIP_N ; 2 = PVDD18_S5_P0
R418  Q_RES  2.2K 5% CHIP  pkg 0402LF  page 27 : 1 = APML_CPU0_ALERT_N ; 2 = PVDD18_S5_P0
R419  Q_RES  0 5% CHIP  pkg 0402LF  page 80 : 1 = RST_SRST_PLD_BMC_N ; 2 = RST_SRST_PLD_BMC_R_N
R420  Q_RES  1K 1% EMPTY  pkg 0402LF  page 28 : 1 = PVDD11_S3_P0 ; 2 = I3C_1_SPD_DDRGL_CPU0_R_SDA
R421  Q_RES  1K 1% EMPTY  pkg 0402LF  page 28 : 1 = PVDD11_S3_P0 ; 2 = I3C_1_SPD_DDRGL_CPU0_R_SCL
R422  Q_RES  2.2K 5% CHIP  pkg 0402LF  page 28 : 1 = PVDD18_S5_P0 ; 2 = RST_CPU0_SYS_N
R423  Q_RES  1K 1% EMPTY  pkg 0402LF  page 28 : 1 = PVDD11_S3_P0 ; 2 = I3C_0_SPD_DDRAF_CPU0_R_SDA
R424  Q_RES  2.2K 5% CHIP  pkg 0402LF  page 28 : 1 = PVDD18_S5_P0 ; 2 = CPU0_PWR_BTN_N
R425  Q_RES  1K 1% EMPTY  pkg 0402LF  page 28 : 1 = PVDD11_S3_P0 ; 2 = I3C_0_SPD_DDRAF_CPU0_R_SCL
R426  Q_RES  0 5% CHIP  pkg 0402LF  page 159 : 1 = I3C_0_SPD_DDRAF_CPU0_SCL ; 2 = I3C_0_SPD_DDRAF_CPU0_R_SCL
R427  Q_RES  0 5% CHIP  pkg 0402LF  page 159 : 1 = I3C_0_SPD_DDRAF_CPU0_SDA ; 2 = I3C_0_SPD_DDRAF_CPU0_R_SDA
R428  Q_RES  0 5% CHIP  pkg 0402LF  page 159 : 1 = I3C_1_SPD_DDRGL_CPU0_SCL ; 2 = I3C_1_SPD_DDRGL_CPU0_R_SCL
R429  Q_RES  0 5% CHIP  pkg 0402LF  page 159 : 1 = I3C_1_SPD_DDRGL_CPU0_SDA ; 2 = I3C_1_SPD_DDRGL_CPU0_R_SDA
R430  Q_RES  0 5% CHIP  pkg 0402LF  page 28 : 1 = SMB_CPU0_4_R_SCL ; 2 = SMB_CPU0_4_SCL
R431  Q_RES  0 5% CHIP  pkg 0402LF  page 28 : 1 = SMB_CPU0_4_R_SDA ; 2 = SMB_CPU0_4_SDA
R432  Q_RES  10M 1% CHIP  pkg 0402LF  page 28 : 1 = XTAL_CPU0_X48M_X1 ; 2 = XTAL_CPU0_X48M_X2_R
R433  Q_RES  20M 1% CHIP  pkg 0402LF  page 28 : 1 = XTAL_CPU0_X32K_X1 ; 2 = XTAL_CPU0_X32K_X2
R434  Q_RES  33 5% CHIP  pkg 0402LF  page 28 : 1 = CPU0_PWR_GD_OUT ; 2 = CPU1_PWR_GD_IN
R435  Q_RES  0 5% CHIP  pkg 0402LF  page 28 : 1 = CLK_100M_REF_OUT_DP ; 2 = CLK_100M_REF_IN_DP
R436  Q_RES  0 5% CHIP  pkg 0402LF  page 28 : 1 = CLK_100M_REF_OUT_DN ; 2 = CLK_100M_REF_IN_DN
R437  Q_RES  2.2K 5% CHIP  pkg 0402LF  page 155 : 1 = PVDD18_S5_P0 ; 2 = IRQ_WAKE_N
R438  Q_RES  4.7K 5% EMPTY  pkg 0402LF  page 28 : 1 = CPU0_FORCE_SELFREFRESH ; 2 = PVDD18_S5_P0
R439  Q_RES  0 5% CHIP  pkg 0402LF  page 80 : 1 = PWRGD_P5V ; 2 = PWRGD_P5V_R2
R440  Q_RES  4.7K 5% EMPTY  pkg 0402LF  page 28 : 1 = GND ; 2 = CPU0_PWR_GD_OUT
R441  Q_RES  2.2K 5% CHIP  pkg 0402LF  page 28 : 1 = CPU0_NMI_SYNC_FLOOD_N ; 2 = PVDD18_S5_P0
R442  Q_RES  1K 1% CHIP  pkg 0402LF  page 28 : 1 = RST_CPU0_RESETL_N ; 2 = PVDD18_S5_P0
R443  Q_RES  1K 1% CHIP  pkg 0402LF  page 28 : 1 = PWRGD_CPU0_PWROK ; 2 = PVDD18_S5_P0
R444  Q_RES  4.7K 5% CHIP  pkg 0402LF  page 28 : 1 = FM_SMM_CRASHDUMP ; 2 = PVDD18_S5_P0
R445  Q_RES  4.7K 5% CHIP  pkg 0402LF  page 28 : 1 = IRQ_BMC_SMI_N ; 2 = PVDD18_S5_P0
R446  Q_RES  4.7K 5% CHIP  pkg 0402LF  page 28 : 1 = IRQ_SMI_ACTIVE_N ; 2 = PVDD18_S5_P0
R447  Q_RES  4.7K 5% CHIP  pkg 0402LF  page 28 : 1 = IRQ_TPM_SPI_R_N ; 2 = PVDD18_S5_P0
R448  Q_RES  4.7K 5% EMPTY  pkg 0402LF  page 28 : 1 = CPU0_SLP_S5_N ; 2 = PVDD18_S5_P0
R449  Q_RES  4.7K 5% EMPTY  pkg 0402LF  page 28 : 1 = CPU0_SLP_S3_N ; 2 = PVDD18_S5_P0
R450  Q_RES  4.7K 5% CHIP  pkg 0402LF  page 28 : 1 = CPU0_SMERR_N ; 2 = PVDD18_S5_P0
R451  Q_RES  4.7K 5% CHIP  pkg 0402LF  page 28 : 1 = CPU0_SPD_HOST_CTRL_N ; 2 = PVDD18_S5_P0
R452  Q_RES  4.7K 5% CHIP  pkg 0402LF  page 28 : 1 = CPU0_NV_SAVE_N ; 2 = PVDD18_S5_P0
R453  Q_RES  10K 5% CHIP  pkg 0402LF  page 192 : 1 = PVDD_33_S5_VCC ; 2 = PWRGD_PVDD33_S5
R454  Q_RES  10K 5% CHIP  pkg 0402LF  page 29 : 1 = PVDD18_S5_P0 ; 2 = SCM_USB_OC_BUF_N
R455  Q_RES  4.7K 5% EMPTY  pkg 0402LF  page 29 : 1 = PVDD18_S5_P0 ; 2 = ESPI_CPU0_CS1_N
R456  Q_RES  4.7K 5% EMPTY  pkg 0402LF  page 55 : 1 = CPU1_PWRGD_OUT ; 2 = PVDD18_S5_P1
R457  Q_RES  4.7K 5% EMPTY  pkg 0402LF  page 29 : 1 = PVDD18_S5_P0 ; 2 = RST_ESPI_CPU0_RSTOUT_N
R458  Q_RES  30K 1% EMPTY  pkg 0402LF  page 29 : 1 = PVDD18_S5_P0 ; 2 = ESPI_CPU0_ALERT_P0_N
R459  Q_RES  33 5% CHIP  pkg 0402LF  page 29 : 1 = SPI_CPU0_CS0_N ; 2 = SPI_CPU0_R_CS0_N
R460  Q_RES  33 5% CHIP  pkg 0402LF  page 29 : 1 = SPI_CPU0_CS1_N ; 2 = SPI_CPU0_R_CS1_N
R461  Q_RES  33 5% CHIP  pkg 0402LF  page 29 : 1 = SPI_CPU0_CLK ; 2 = SPI_CPU0_R_CLK
R462  Q_RES  33 5% EMPTY  pkg 0402LF  page 29 : 1 = ESPI_CPU0_CS1_N ; 2 = ESPI_CPU0_R_CS1_N
R463  Q_RES  33 5% CHIP  pkg 0402LF  page 81 : 1 = RST_CPU0_KBRST_R_N ; 2 = RST_CPU0_KBRST_N
R464  Q_RES  33 5% CHIP  pkg 0402LF  page 29 : 1 = SPI_CPU0_D0 ; 2 = SPI_CPU0_R_D0
